# T6G (Grand Teton) — schematic netlist excerpt (pin names and nets, part order shuffled) for the footprints in the layout excerpt that follows; sources: Cadence DE-HDL packaged netlist, KiCad conversion of 04192023_DAF0TMB3IC0_F0TG_MB_C_brd_V02_OCP.brd

R92  Q_RES  1K 1% EMPTY  pkg 0402LF  page 89 : A = P3V3 ; B = PWRGD_CHD_CPU0_DIMM
R3093  Q_RES  130 1% CHIP  pkg 0402LF  page 256 : A = LED_PWRGD_PVDDCR_CPU0_P1_R ; B = P3V3_AUX
C391  Q_CAP  1UF 4V 20% X6S  pkg 0201  page 345 : A = P0V9_CPU1_RT2_2A ; B = GND

(kicad_pcb
	(version 20260206)
	(generator "pcbnew")
	(generator_version "10.0")
	(general
		(thickness 1.6)
		(legacy_teardrops no)
	)
	(paper "A4")
	(title_block
		(title "04192023_DAF0TMB3IC0_F0TG_MB_C_brd_V02_OCP.brd")
		(comment 1 "Grand Teton / footprints 5909-5911 of 8354")
	)
	(layers
		(0 "F.Cu" signal "TOP")
		(4 "In1.Cu" signal "GND")
		(6 "In2.Cu" signal "IN1")
		(8 "In3.Cu" signal "GND1")
		(10 "In4.Cu" signal "IN2")
		(12 "In5.Cu" signal "GND2")
		(14 "In6.Cu" signal "IN3")
		(16 "In7.Cu" signal "GND3")
		(18 "In8.Cu" signal "VCC")
		(20 "In9.Cu" signal "VCC1")
		(22 "In10.Cu" signal "GND4")
		(24 "In11.Cu" signal "IN4")
		(26 "In12.Cu" signal "GND5")
		(28 "In13.Cu" signal "IN5")
		(30 "In14.Cu" signal "GND6")
		(32 "In15.Cu" signal "IN6")
		(34 "In16.Cu" signal "GND7")
		(2 "B.Cu" signal "BOTTOM")
		(9 "F.Adhes" user "F.Adhesive")
		(11 "B.Adhes" user "B.Adhesive")
		(13 "F.Paste" user "Package Geometry/Pastemask Top")
		(15 "B.Paste" user "Package Geometry/Pastemask Bottom")
		(5 "F.SilkS" user "Ref Des/Silkscreen Top")
		(7 "B.SilkS" user "Ref Des/Silkscreen Bottom")
		(1 "F.Mask" user "Board Geometry/Soldermask Top")
		(3 "B.Mask" user "Board Geometry/Soldermask Bottom")
		(17 "Dwgs.User" user "User.Drawings")
		(19 "Cmts.User" user "User.Comments")
		(21 "Eco1.User" user "User.Eco1")
		(23 "Eco2.User" user "User.Eco2")
		(25 "Edge.Cuts" user "Board Geometry/Outline")
		(27 "Margin" user)
		(31 "F.CrtYd" user "Package Geometry/Place Bound Top")
		(29 "B.CrtYd" user "Package Geometry/Place Bound Bottom")
		(35 "F.Fab" user "Ref Des/Assembly Top")
		(33 "B.Fab" user "Ref Des/Assembly Bottom")
	)
	(footprint ""
		(layer "B.Cu")
		(at 336.827876 -66.708782 90)
		(property "Reference" "R3093"
			(at 0 0 90)
			(layer "B.SilkS")
			(hide yes)
			(effects
				(font
					(size 1.27 1.27)
				)
				(justify mirror)
			)
		)
		(property "Value" ""
			(at 0 0 90)
			(layer "B.Fab")
			(effects
				(font
					(size 1.27 1.27)
				)
				(justify mirror)
			)
		)
		(duplicate_pad_numbers_are_jumpers no)
		(fp_line
			(start 0.7874 -0.4064)
			(end -0.7874 -0.4064)
			(stroke
				(width 0.1524)
				(type default)
			)
			(layer "B.SilkS")
		)
		(fp_line
			(start -0.7874 -0.4064)
			(end -0.7874 0.4064)
			(stroke
				(width 0.1524)
				(type default)
			)
			(layer "B.SilkS")
		)
		(fp_line
			(start 0.7874 0.4064)
			(end 0.7874 -0.4064)
			(stroke
				(width 0.1524)
				(type default)
			)
			(layer "B.SilkS")
		)
		(fp_line
			(start -0.7874 0.4064)
			(end 0.7874 0.4064)
			(stroke
				(width 0.1524)
				(type default)
			)
			(layer "B.SilkS")
		)
		(fp_line
			(start 0.67945 -0.305054)
			(end 0.12065 -0.305054)
			(stroke
				(width 0.1)
				(type default)
			)
			(layer "B.Fab")
		)
		(fp_line
			(start 0.12065 -0.305054)
			(end 0.12065 -0.2794)
			(stroke
				(width 0.1)
				(type default)
			)
			(layer "B.Fab")
		)
		(fp_line
			(start -0.12065 -0.3048)
			(end -0.67945 -0.3048)
			(stroke
				(width 0.1)
				(type default)
			)
			(layer "B.Fab")
		)
		(fp_line
			(start -0.67945 -0.3048)
			(end -0.67945 0.3048)
			(stroke
				(width 0.1)
				(type default)
			)
			(layer "B.Fab")
		)
		(fp_line
			(start 0.12065 -0.2794)
			(end -0.12065 -0.2794)
			(stroke
				(width 0.1)
				(type default)
			)
			(layer "B.Fab")
		)
		(fp_line
			(start -0.12065 -0.2794)
			(end -0.12065 -0.3048)
			(stroke
				(width 0.1)
				(type default)
			)
			(layer "B.Fab")
		)
		(fp_line
			(start 0.12065 0.2794)
			(end 0.12065 0.3048)
			(stroke
				(width 0.1)
				(type default)
			)
			(layer "B.Fab")
		)
		(fp_line
			(start -0.120396 0.2794)
			(end 0.12065 0.2794)
			(stroke
				(width 0.1)
				(type default)
			)
			(layer "B.Fab")
		)
		(fp_line
			(start 0.67945 0.3048)
			(end 0.67945 -0.305054)
			(stroke
				(width 0.1)
				(type default)
			)
			(layer "B.Fab")
		)
		(fp_line
			(start 0.12065 0.3048)
			(end 0.67945 0.3048)
			(stroke
				(width 0.1)
				(type default)
			)
			(layer "B.Fab")
		)
		(fp_line
			(start -0.120396 0.3048)
			(end -0.120396 0.2794)
			(stroke
				(width 0.1)
				(type default)
			)
			(layer "B.Fab")
		)
		(fp_line
			(start -0.67945 0.3048)
			(end -0.120396 0.3048)
			(stroke
				(width 0.1)
				(type default)
			)
			(layer "B.Fab")
		)
		(pad "1" smd circle
			(at 0.40005 0 270)
			(size 0 0)
			(layers "B.Cu" "B.Mask" "B.Paste")
			(net "LED_PWRGD_PVDDCR_CPU0_P1_R")
		)
		(pad "2" smd circle
			(at -0.40005 0 270)
			(size 0 0)
			(layers "B.Cu" "B.Mask" "B.Paste")
			(net "P3V3_AUX")
		)
	)
	(footprint ""
		(layer "B.Cu")
		(at 162.606228 -386.766562 90)
		(property "Reference" "C391"
			(at 0 0 90)
			(layer "B.SilkS")
			(hide yes)
			(effects
				(font
					(size 1.27 1.27)
				)
				(justify mirror)
			)
		)
		(property "Value" ""
			(at 0 0 90)
			(layer "B.Fab")
			(effects
				(font
					(size 1.27 1.27)
				)
				(justify mirror)
			)
		)
		(duplicate_pad_numbers_are_jumpers no)
		(fp_line
			(start 0.299974 -0.150114)
			(end -0.299974 -0.150114)
			(stroke
				(width 0.1)
				(type default)
			)
			(layer "B.Fab")
		)
		(fp_line
			(start -0.299974 -0.150114)
			(end -0.299974 0.150114)
			(stroke
				(width 0.1)
				(type default)
			)
			(layer "B.Fab")
		)
		(fp_line
			(start 0.299974 0.150114)
			(end 0.299974 -0.150114)
			(stroke
				(width 0.1)
				(type default)
			)
			(layer "B.Fab")
		)
		(fp_line
			(start -0.299974 0.150114)
			(end 0.299974 0.150114)
			(stroke
				(width 0.1)
				(type default)
			)
			(layer "B.Fab")
		)
		(pad "1" smd rect
			(at 0.2667 0 270)
			(size 0.3048 0.381)
			(layers "B.Cu" "B.Mask" "B.Paste")
			(net "P0V9_CPU1_RT2_2A")
		)
		(pad "2" smd rect
			(at -0.2667 0 270)
			(size 0.3048 0.381)
			(layers "B.Cu" "B.Mask" "B.Paste")
			(net "GND")
		)
	)
	(footprint ""
		(layer "B.Cu")
		(at 281.391614 -193.99631)
		(property "Reference" "R92"
			(at 0 0 0)
			(layer "B.SilkS")
			(hide yes)
			(effects
				(font
					(size 1.27 1.27)
				)
				(justify mirror)
			)
		)
		(property "Value" ""
			(at 0 0 0)
			(layer "B.Fab")
			(effects
				(font
					(size 1.27 1.27)
				)
				(justify mirror)
			)
		)
		(duplicate_pad_numbers_are_jumpers no)
		(fp_line
			(start -0.7874 -0.4064)
			(end -0.7874 0.4064)
			(stroke
				(width 0.1524)
				(type default)
			)
			(layer "B.SilkS")
		)
		(fp_line
			(start -0.7874 0.4064)
			(end 0.7874 0.4064)
			(stroke
				(width 0.1524)
				(type default)
			)
			(layer "B.SilkS")
		)
		(fp_line
			(start 0.7874 -0.4064)
			(end -0.7874 -0.4064)
			(stroke
				(width 0.1524)
				(type default)
			)
			(layer "B.SilkS")
		)
		(fp_line
			(start 0.7874 0.4064)
			(end 0.7874 -0.4064)
			(stroke
				(width 0.1524)
				(type default)
			)
			(layer "B.SilkS")
		)
		(fp_line
			(start -0.67945 -0.3048)
			(end -0.67945 0.3048)
			(stroke
				(width 0.1)
				(type default)
			)
			(layer "B.Fab")
		)
		(fp_line
			(start -0.67945 0.3048)
			(end -0.120396 0.3048)
			(stroke
				(width 0.1)
				(type default)
			)
			(layer "B.Fab")
		)
		(fp_line
			(start -0.12065 -0.3048)
			(end -0.67945 -0.3048)
			(stroke
				(width 0.1)
				(type default)
			)
			(layer "B.Fab")
		)
		(fp_line
			(start -0.12065 -0.2794)
			(end -0.12065 -0.3048)
			(stroke
				(width 0.1)
				(type default)
			)
			(layer "B.Fab")
		)
		(fp_line
			(start -0.120396 0.2794)
			(end 0.12065 0.2794)
			(stroke
				(width 0.1)
				(type default)
			)
			(layer "B.Fab")
		)
		(fp_line
			(start -0.120396 0.3048)
			(end -0.120396 0.2794)
			(stroke
				(width 0.1)
				(type default)
			)
			(layer "B.Fab")
		)
		(fp_line
			(start 0.12065 -0.305054)
			(end 0.12065 -0.2794)
			(stroke
				(width 0.1)
				(type default)
			)
			(layer "B.Fab")
		)
		(fp_line
			(start 0.12065 -0.2794)
			(end -0.12065 -0.2794)
			(stroke
				(width 0.1)
				(type default)
			)
			(layer "B.Fab")
		)
		(fp_line
			(start 0.12065 0.2794)
			(end 0.12065 0.3048)
			(stroke
				(width 0.1)
				(type default)
			)
			(layer "B.Fab")
		)
		(fp_line
			(start 0.12065 0.3048)
			(end 0.67945 0.3048)
			(stroke
				(width 0.1)
				(type default)
			)
			(layer "B.Fab")
		)
		(fp_line
			(start 0.67945 -0.305054)
			(end 0.12065 -0.305054)
			(stroke
				(width 0.1)
				(type default)
			)
			(layer "B.Fab")
		)
		(fp_line
			(start 0.67945 0.3048)
			(end 0.67945 -0.305054)
			(stroke
				(width 0.1)
				(type default)
			)
			(layer "B.Fab")
		)
		(pad "1" smd circle
			(at 0.40005 0 180)
			(size 0 0)
			(layers "B.Cu" "B.Mask" "B.Paste")
			(net "P3V3")
		)
		(pad "2" smd circle
			(at -0.40005 0 180)
			(size 0 0)
			(layers "B.Cu" "B.Mask" "B.Paste")
			(net "PWRGD_CHD_CPU0_DIMM")
		)
	)
)
